(kicad_pcb
	(version 20260206)
	(generator "pcbnew")
	(generator_version "10.0")
	(general
		(thickness 1.6)
		(legacy_teardrops no)
	)
	(paper "A4")
	(title_block
		(title "baseboard — 13948-1b.1110WZS1818.brd")
		(comment 1 "Honey Badger (Wiwynn) / footprints 258-265 of 2523")
	)
	(layers
		(0 "F.Cu" signal "TOP")
		(4 "In1.Cu" signal "L2GND")
		(6 "In2.Cu" signal "L3")
		(8 "In3.Cu" signal "L4VCC")
		(10 "In4.Cu" signal "L5VCC")
		(12 "In5.Cu" signal "L6")
		(14 "In6.Cu" signal "L7GND")
		(2 "B.Cu" signal "BOTTOM")
		(9 "F.Adhes" user "F.Adhesive")
		(11 "B.Adhes" user "B.Adhesive")
		(13 "F.Paste" user "Package Geometry/Pastemask Top")
		(15 "B.Paste" user "Package Geometry/Pastemask Bottom")
		(5 "F.SilkS" user "Ref Des/Silkscreen Top")
		(7 "B.SilkS" user "Ref Des/Silkscreen Bottom")
		(1 "F.Mask" user "Board Geometry/Soldermask Top")
		(3 "B.Mask" user "Board Geometry/Soldermask Bottom")
		(17 "Dwgs.User" user "User.Drawings")
		(19 "Cmts.User" user "User.Comments")
		(21 "Eco1.User" user "User.Eco1")
		(23 "Eco2.User" user "User.Eco2")
		(25 "Edge.Cuts" user "Board Geometry/Outline")
		(27 "Margin" user)
		(31 "F.CrtYd" user "Package Geometry/Place Bound Top")
		(29 "B.CrtYd" user "Package Geometry/Place Bound Bottom")
		(35 "F.Fab" user "Ref Des/Assembly Top")
		(33 "B.Fab" user "Ref Des/Assembly Bottom")
	)
	(footprint ""
		(layer "F.Cu")
		(at 279.273 -191.77 180)
		(property "Reference" "C202"
			(at 0 0 180)
			(layer "F.SilkS")
			(hide yes)
			(effects
				(font
					(size 1.27 1.27)
				)
			)
		)
		(property "Value" "SCD1U16V2KX-3GP"
			(at 1.1811 -2.7051 180)
			(unlocked yes)
			(layer "F.Fab")
			(hide yes)
			(effects
				(font
					(size 1.016 1.016)
					(thickness 0.1524)
				)
			)
		)
		(property "Device Type" "C402H22"
			(at 1.1811 -4.2291 180)
			(unlocked yes)
			(layer "F.Fab")
			(hide yes)
			(effects
				(font
					(size 1.016 1.016)
					(thickness 0.1524)
				)
			)
		)
		(duplicate_pad_numbers_are_jumpers no)
		(fp_rect
			(start -0.4318 0.9525)
			(end 0.4318 -0.9525)
			(stroke
				(width 0)
				(type default)
			)
			(fill no)
			(layer "F.CrtYd")
		)
		(fp_rect
			(start -0.4318 0.9525)
			(end 0.4318 -0.9525)
			(stroke
				(width 0)
				(type default)
			)
			(fill no)
			(layer "F.Fab")
		)
		(pad "1" smd custom
			(at 0 -0.4445 180)
			(size 0.1524 0.1524)
			(layers "F.Cu" "F.Mask" "F.Paste")
			(net "V1PLLAV12")
			(options
				(clearance outline)
				(anchor circle)
			)
			(primitives
				(gr_poly
					(pts
						(arc
							(start 0.3048 -0.2032)
							(mid 0.275042 -0.275042)
							(end 0.2032 -0.3048)
						)
						(arc
							(start -0.2032 -0.3048)
							(mid -0.275042 -0.275042)
							(end -0.3048 -0.2032)
						)
						(arc
							(start -0.3048 0.2032)
							(mid -0.275042 0.275042)
							(end -0.2032 0.3048)
						)
						(arc
							(start 0.2032 0.3048)
							(mid 0.275042 0.275042)
							(end 0.3048 0.2032)
						)
					)
					(width 0)
					(fill yes)
				)
			)
		)
		(pad "2" smd custom
			(at 0 0.4445 180)
			(size 0.1524 0.1524)
			(layers "F.Cu" "F.Mask" "F.Paste")
			(net "GND")
			(options
				(clearance outline)
				(anchor circle)
			)
			(primitives
				(gr_poly
					(pts
						(arc
							(start 0.3048 -0.2032)
							(mid 0.275042 -0.275042)
							(end 0.2032 -0.3048)
						)
						(arc
							(start -0.2032 -0.3048)
							(mid -0.275042 -0.275042)
							(end -0.3048 -0.2032)
						)
						(arc
							(start -0.3048 0.2032)
							(mid -0.275042 0.275042)
							(end -0.2032 0.3048)
						)
						(arc
							(start 0.2032 0.3048)
							(mid 0.275042 0.275042)
							(end 0.3048 0.2032)
						)
					)
					(width 0)
					(fill yes)
				)
			)
		)
	)
	(footprint ""
		(layer "F.Cu")
		(at 193.167 -14.097 -90)
		(property "Reference" "R5306"
			(at 0 0 270)
			(layer "F.SilkS")
			(hide yes)
			(effects
				(font
					(size 1.27 1.27)
				)
			)
		)
		(property "Value" "0R2J-2-GP"
			(at 0.064008 -3.993896 270)
			(unlocked yes)
			(layer "F.Fab")
			(hide yes)
			(effects
				(font
					(size 1.016 1.016)
					(thickness 0.1524)
				)
			)
		)
		(property "Device Type" "R402H16"
			(at 0.064008 -5.517896 270)
			(unlocked yes)
			(layer "F.Fab")
			(hide yes)
			(effects
				(font
					(size 1.016 1.016)
					(thickness 0.1524)
				)
			)
		)
		(duplicate_pad_numbers_are_jumpers no)
		(fp_line
			(start -0.508 -0.9398)
			(end -0.508 0.9398)
			(stroke
				(width 0.1524)
				(type default)
			)
			(layer "F.SilkS")
		)
		(fp_line
			(start 0.508 -0.9398)
			(end -0.508 -0.9398)
			(stroke
				(width 0.1524)
				(type default)
			)
			(layer "F.SilkS")
		)
		(fp_rect
			(start -0.508 0.9398)
			(end 0.508 -0.9398)
			(stroke
				(width 0)
				(type default)
			)
			(fill no)
			(layer "F.CrtYd")
		)
		(fp_rect
			(start -0.508 0.9398)
			(end 0.508 -0.9398)
			(stroke
				(width 0)
				(type default)
			)
			(fill no)
			(layer "F.Fab")
		)
		(pad "1" smd custom
			(at 0 -0.4445 270)
			(size 0.1397 0.1397)
			(layers "F.Cu" "F.Mask" "F.Paste")
			(net "BMC_I2C_SDA_10")
			(options
				(clearance outline)
				(anchor circle)
			)
			(primitives
				(gr_poly
					(pts
						(arc
							(start -0.1778 -0.2794)
							(mid -0.249642 -0.249642)
							(end -0.2794 -0.1778)
						)
						(arc
							(start -0.2794 0.1778)
							(mid -0.249642 0.249642)
							(end -0.1778 0.2794)
						)
						(arc
							(start 0.1778 0.2794)
							(mid 0.249642 0.249642)
							(end 0.2794 0.1778)
						)
						(arc
							(start 0.2794 -0.1778)
							(mid 0.249642 -0.249642)
							(end 0.1778 -0.2794)
						)
					)
					(width 0)
					(fill yes)
				)
			)
		)
		(pad "2" smd custom
			(at 0 0.4445 270)
			(size 0.1397 0.1397)
			(layers "F.Cu" "F.Mask" "F.Paste")
			(net "TEMP_1_SDA")
			(options
				(clearance outline)
				(anchor circle)
			)
			(primitives
				(gr_poly
					(pts
						(arc
							(start -0.1778 -0.2794)
							(mid -0.249642 -0.249642)
							(end -0.2794 -0.1778)
						)
						(arc
							(start -0.2794 0.1778)
							(mid -0.249642 0.249642)
							(end -0.1778 0.2794)
						)
						(arc
							(start 0.1778 0.2794)
							(mid 0.249642 0.249642)
							(end 0.2794 0.1778)
						)
						(arc
							(start 0.2794 -0.1778)
							(mid 0.249642 -0.249642)
							(end 0.1778 -0.2794)
						)
					)
					(width 0)
					(fill yes)
				)
			)
		)
	)
	(footprint ""
		(layer "F.Cu")
		(at 80.372966 -89.916 90)
		(property "Reference" "SR838"
			(at 0 0 90)
			(layer "F.SilkS")
			(hide yes)
			(effects
				(font
					(size 1.27 1.27)
				)
			)
		)
		(property "Value" "10R2F-L-GP"
			(at 0.064008 -3.993896 90)
			(unlocked yes)
			(layer "F.Fab")
			(hide yes)
			(effects
				(font
					(size 1.016 1.016)
					(thickness 0.1524)
				)
			)
		)
		(property "Device Type" "R402H14"
			(at 0.064008 -5.517896 90)
			(unlocked yes)
			(layer "F.Fab")
			(hide yes)
			(effects
				(font
					(size 1.016 1.016)
					(thickness 0.1524)
				)
			)
		)
		(duplicate_pad_numbers_are_jumpers no)
		(fp_line
			(start 0.508 -0.9398)
			(end -0.508 -0.9398)
			(stroke
				(width 0.1524)
				(type default)
			)
			(layer "F.SilkS")
		)
		(fp_line
			(start -0.508 -0.9398)
			(end -0.508 0.9398)
			(stroke
				(width 0.1524)
				(type default)
			)
			(layer "F.SilkS")
		)
		(fp_rect
			(start -0.508 0.9398)
			(end 0.508 -0.9398)
			(stroke
				(width 0)
				(type default)
			)
			(fill no)
			(layer "F.CrtYd")
		)
		(fp_rect
			(start -0.508 0.9398)
			(end 0.508 -0.9398)
			(stroke
				(width 0)
				(type default)
			)
			(fill no)
			(layer "F.Fab")
		)
		(pad "1" smd custom
			(at 0 -0.4445 90)
			(size 0.1397 0.1397)
			(layers "F.Cu" "F.Mask" "F.Paste")
			(net "P0V9_E")
			(options
				(clearance outline)
				(anchor circle)
			)
			(primitives
				(gr_poly
					(pts
						(arc
							(start -0.1778 -0.2794)
							(mid -0.249642 -0.249642)
							(end -0.2794 -0.1778)
						)
						(arc
							(start -0.2794 0.1778)
							(mid -0.249642 0.249642)
							(end -0.1778 0.2794)
						)
						(arc
							(start 0.1778 0.2794)
							(mid 0.249642 0.249642)
							(end 0.2794 0.1778)
						)
						(arc
							(start 0.2794 -0.1778)
							(mid 0.249642 -0.249642)
							(end 0.1778 -0.2794)
						)
					)
					(width 0)
					(fill yes)
				)
			)
		)
		(pad "2" smd custom
			(at 0 0.4445 90)
			(size 0.1397 0.1397)
			(layers "F.Cu" "F.Mask" "F.Paste")
			(net "SYSPLL_VDDA09")
			(options
				(clearance outline)
				(anchor circle)
			)
			(primitives
				(gr_poly
					(pts
						(arc
							(start -0.1778 -0.2794)
							(mid -0.249642 -0.249642)
							(end -0.2794 -0.1778)
						)
						(arc
							(start -0.2794 0.1778)
							(mid -0.249642 0.249642)
							(end -0.1778 0.2794)
						)
						(arc
							(start 0.1778 0.2794)
							(mid 0.249642 0.249642)
							(end 0.2794 0.1778)
						)
						(arc
							(start 0.2794 -0.1778)
							(mid 0.249642 -0.249642)
							(end 0.1778 -0.2794)
						)
					)
					(width 0)
					(fill yes)
				)
			)
		)
	)
	(footprint ""
		(layer "F.Cu")
		(at 289.932872 -218.004136 -90)
		(property "Reference" "PR79"
			(at 0 0 270)
			(layer "F.SilkS")
			(hide yes)
			(effects
				(font
					(size 1.27 1.27)
				)
			)
		)
		(property "Value" "4K42R2F-GP"
			(at 0.064008 -3.993896 270)
			(unlocked yes)
			(layer "F.Fab")
			(hide yes)
			(effects
				(font
					(size 1.016 1.016)
					(thickness 0.1524)
				)
			)
		)
		(property "Device Type" "R402H16"
			(at 0.064008 -5.517896 270)
			(unlocked yes)
			(layer "F.Fab")
			(hide yes)
			(effects
				(font
					(size 1.016 1.016)
					(thickness 0.1524)
				)
			)
		)
		(duplicate_pad_numbers_are_jumpers no)
		(fp_line
			(start -0.508 -0.9398)
			(end -0.508 0.9398)
			(stroke
				(width 0.1524)
				(type default)
			)
			(layer "F.SilkS")
		)
		(fp_line
			(start 0.508 -0.9398)
			(end -0.508 -0.9398)
			(stroke
				(width 0.1524)
				(type default)
			)
			(layer "F.SilkS")
		)
		(fp_rect
			(start -0.508 0.9398)
			(end 0.508 -0.9398)
			(stroke
				(width 0)
				(type default)
			)
			(fill no)
			(layer "F.CrtYd")
		)
		(fp_rect
			(start -0.508 0.9398)
			(end 0.508 -0.9398)
			(stroke
				(width 0)
				(type default)
			)
			(fill no)
			(layer "F.Fab")
		)
		(pad "1" smd custom
			(at 0 -0.4445 270)
			(size 0.1397 0.1397)
			(layers "F.Cu" "F.Mask" "F.Paste")
			(net "TPS74801_1V53_STBY_OUT")
			(options
				(clearance outline)
				(anchor circle)
			)
			(primitives
				(gr_poly
					(pts
						(arc
							(start -0.1778 -0.2794)
							(mid -0.249642 -0.249642)
							(end -0.2794 -0.1778)
						)
						(arc
							(start -0.2794 0.1778)
							(mid -0.249642 0.249642)
							(end -0.1778 0.2794)
						)
						(arc
							(start 0.1778 0.2794)
							(mid 0.249642 0.249642)
							(end 0.2794 0.1778)
						)
						(arc
							(start 0.2794 -0.1778)
							(mid 0.249642 -0.249642)
							(end 0.1778 -0.2794)
						)
					)
					(width 0)
					(fill yes)
				)
			)
		)
		(pad "2" smd custom
			(at 0 0.4445 270)
			(size 0.1397 0.1397)
			(layers "F.Cu" "F.Mask" "F.Paste")
			(net "TPS74801_1V53_STBY_FB")
			(options
				(clearance outline)
				(anchor circle)
			)
			(primitives
				(gr_poly
					(pts
						(arc
							(start -0.1778 -0.2794)
							(mid -0.249642 -0.249642)
							(end -0.2794 -0.1778)
						)
						(arc
							(start -0.2794 0.1778)
							(mid -0.249642 0.249642)
							(end -0.1778 0.2794)
						)
						(arc
							(start 0.1778 0.2794)
							(mid 0.249642 0.249642)
							(end 0.2794 0.1778)
						)
						(arc
							(start 0.2794 -0.1778)
							(mid 0.249642 -0.249642)
							(end 0.1778 -0.2794)
						)
					)
					(width 0)
					(fill yes)
				)
			)
		)
	)
	(footprint ""
		(layer "F.Cu")
		(at 191.897 -25.273 -90)
		(property "Reference" "R442"
			(at 0 0 270)
			(layer "F.SilkS")
			(hide yes)
			(effects
				(font
					(size 1.27 1.27)
				)
			)
		)
		(property "Value" "0R2J-2-GP"
			(at 0.064008 -3.993896 270)
			(unlocked yes)
			(layer "F.Fab")
			(hide yes)
			(effects
				(font
					(size 1.016 1.016)
					(thickness 0.1524)
				)
			)
		)
		(property "Device Type" "R402H16"
			(at 0.064008 -5.517896 270)
			(unlocked yes)
			(layer "F.Fab")
			(hide yes)
			(effects
				(font
					(size 1.016 1.016)
					(thickness 0.1524)
				)
			)
		)
		(duplicate_pad_numbers_are_jumpers no)
		(fp_line
			(start -0.508 -0.9398)
			(end -0.508 0.9398)
			(stroke
				(width 0.1524)
				(type default)
			)
			(layer "F.SilkS")
		)
		(fp_line
			(start 0.508 -0.9398)
			(end -0.508 -0.9398)
			(stroke
				(width 0.1524)
				(type default)
			)
			(layer "F.SilkS")
		)
		(fp_rect
			(start -0.508 0.9398)
			(end 0.508 -0.9398)
			(stroke
				(width 0)
				(type default)
			)
			(fill no)
			(layer "F.CrtYd")
		)
		(fp_rect
			(start -0.508 0.9398)
			(end 0.508 -0.9398)
			(stroke
				(width 0)
				(type default)
			)
			(fill no)
			(layer "F.Fab")
		)
		(pad "1" smd custom
			(at 0 -0.4445 270)
			(size 0.1397 0.1397)
			(layers "F.Cu" "F.Mask" "F.Paste")
			(net "GND")
			(options
				(clearance outline)
				(anchor circle)
			)
			(primitives
				(gr_poly
					(pts
						(arc
							(start -0.1778 -0.2794)
							(mid -0.249642 -0.249642)
							(end -0.2794 -0.1778)
						)
						(arc
							(start -0.2794 0.1778)
							(mid -0.249642 0.249642)
							(end -0.1778 0.2794)
						)
						(arc
							(start 0.1778 0.2794)
							(mid 0.249642 0.249642)
							(end 0.2794 0.1778)
						)
						(arc
							(start 0.2794 -0.1778)
							(mid 0.249642 -0.249642)
							(end 0.1778 -0.2794)
						)
					)
					(width 0)
					(fill yes)
				)
			)
		)
		(pad "2" smd custom
			(at 0 0.4445 270)
			(size 0.1397 0.1397)
			(layers "F.Cu" "F.Mask" "F.Paste")
			(net "RMII_PHY_BMC_RXD0")
			(options
				(clearance outline)
				(anchor circle)
			)
			(primitives
				(gr_poly
					(pts
						(arc
							(start -0.1778 -0.2794)
							(mid -0.249642 -0.249642)
							(end -0.2794 -0.1778)
						)
						(arc
							(start -0.2794 0.1778)
							(mid -0.249642 0.249642)
							(end -0.1778 0.2794)
						)
						(arc
							(start 0.1778 0.2794)
							(mid 0.249642 0.249642)
							(end 0.2794 0.1778)
						)
						(arc
							(start 0.2794 -0.1778)
							(mid 0.249642 -0.249642)
							(end 0.1778 -0.2794)
						)
					)
					(width 0)
					(fill yes)
				)
			)
		)
	)
	(footprint ""
		(layer "F.Cu")
		(at 171.598844 -27.399996 -90)
		(property "Reference" "C237"
			(at 0 0 270)
			(layer "F.SilkS")
			(hide yes)
			(effects
				(font
					(size 1.27 1.27)
				)
			)
		)
		(property "Value" "SCD1U16V2KX-3GP"
			(at 1.1811 -2.7051 270)
			(unlocked yes)
			(layer "F.Fab")
			(hide yes)
			(effects
				(font
					(size 1.016 1.016)
					(thickness 0.1524)
				)
			)
		)
		(property "Device Type" "C402H22"
			(at 1.1811 -4.2291 270)
			(unlocked yes)
			(layer "F.Fab")
			(hide yes)
			(effects
				(font
					(size 1.016 1.016)
					(thickness 0.1524)
				)
			)
		)
		(duplicate_pad_numbers_are_jumpers no)
		(fp_rect
			(start -0.4318 0.9525)
			(end 0.4318 -0.9525)
			(stroke
				(width 0)
				(type default)
			)
			(fill no)
			(layer "F.CrtYd")
		)
		(fp_rect
			(start -0.4318 0.9525)
			(end 0.4318 -0.9525)
			(stroke
				(width 0)
				(type default)
			)
			(fill no)
			(layer "F.Fab")
		)
		(pad "1" smd custom
			(at 0 -0.4445 270)
			(size 0.1524 0.1524)
			(layers "F.Cu" "F.Mask" "F.Paste")
			(net "MOD_IMC_FAB_D_COP")
			(options
				(clearance outline)
				(anchor circle)
			)
			(primitives
				(gr_poly
					(pts
						(arc
							(start 0.3048 -0.2032)
							(mid 0.275042 -0.275042)
							(end 0.2032 -0.3048)
						)
						(arc
							(start -0.2032 -0.3048)
							(mid -0.275042 -0.275042)
							(end -0.3048 -0.2032)
						)
						(arc
							(start -0.3048 0.2032)
							(mid -0.275042 0.275042)
							(end -0.2032 0.3048)
						)
						(arc
							(start 0.2032 0.3048)
							(mid 0.275042 0.275042)
							(end 0.3048 0.2032)
						)
					)
					(width 0)
					(fill yes)
				)
			)
		)
		(pad "2" smd custom
			(at 0 0.4445 270)
			(size 0.1524 0.1524)
			(layers "F.Cu" "F.Mask" "F.Paste")
			(net "GND")
			(options
				(clearance outline)
				(anchor circle)
			)
			(primitives
				(gr_poly
					(pts
						(arc
							(start 0.3048 -0.2032)
							(mid 0.275042 -0.275042)
							(end 0.2032 -0.3048)
						)
						(arc
							(start -0.2032 -0.3048)
							(mid -0.275042 -0.275042)
							(end -0.3048 -0.2032)
						)
						(arc
							(start -0.3048 0.2032)
							(mid -0.275042 0.275042)
							(end -0.2032 0.3048)
						)
						(arc
							(start 0.2032 0.3048)
							(mid 0.275042 0.275042)
							(end 0.3048 0.2032)
						)
					)
					(width 0)
					(fill yes)
				)
			)
		)
	)
	(footprint ""
		(layer "F.Cu")
		(at 116.09197 -78.232)
		(property "Reference" "STP109"
			(at 0 0 0)
			(layer "F.SilkS")
			(hide yes)
			(effects
				(font
					(size 1.27 1.27)
				)
			)
		)
		(property "Value" "TPAD28"
			(at 0.0127 -1.8034 0)
			(unlocked yes)
			(layer "F.Fab")
			(hide yes)
			(effects
				(font
					(size 1.016 1.016)
					(thickness 0.1524)
				)
			)
		)
		(property "Device Type" "TPAD28"
			(at 0.0127 -3.3274 0)
			(unlocked yes)
			(layer "F.Fab")
			(hide yes)
			(effects
				(font
					(size 1.016 1.016)
					(thickness 0.1524)
				)
			)
		)
		(duplicate_pad_numbers_are_jumpers no)
		(fp_poly
			(pts
				(arc
					(start 0.3556 0)
					(mid -0.3556 0)
					(end 0.3556 0)
				)
			)
			(stroke
				(width 0)
				(type default)
			)
			(fill no)
			(layer "F.CrtYd")
		)
		(fp_poly
			(pts
				(arc
					(start 0.6096 0)
					(mid -0.6096 0)
					(end 0.6096 0)
				)
			)
			(stroke
				(width 0)
				(type default)
			)
			(fill no)
			(layer "F.Fab")
		)
		(pad "1" smd circle
			(at 0 0)
			(size 0.7112 0.7112)
			(layers "F.Cu" "F.Mask" "F.Paste")
			(net "TEST_MUX_42")
		)
	)
	(footprint ""
		(layer "F.Cu")
		(at 199.644 -216.789 90)
		(property "Reference" "U173"
			(at 0 0 90)
			(layer "F.SilkS")
			(hide yes)
			(effects
				(font
					(size 1.27 1.27)
				)
			)
		)
		(property "Value" "SN74LVC1G08DCKR-GP"
			(at -2.3368 -8.6868 90)
			(unlocked yes)
			(layer "F.Fab")
			(hide yes)
			(effects
				(font
					(size 1.016 1.016)
					(thickness 0.1524)
				)
			)
		)
		(property "Device Type" "SC70-5H44"
			(at -2.3114 -10.414 90)
			(unlocked yes)
			(layer "F.Fab")
			(hide yes)
			(effects
				(font
					(size 1.016 1.016)
					(thickness 0.1524)
				)
			)
		)
		(duplicate_pad_numbers_are_jumpers no)
		(fp_line
			(start 1.3843 -1.8034)
			(end 1.3843 -1.1176)
			(stroke
				(width 0.3302)
				(type default)
			)
			(layer "F.SilkS")
		)
		(fp_line
			(start 0.6604 -1.8034)
			(end 1.3843 -1.8034)
			(stroke
				(width 0.3302)
				(type default)
			)
			(layer "F.SilkS")
		)
		(fp_line
			(start 1.27 -1.7018)
			(end 1.27 1.7018)
			(stroke
				(width 0.1524)
				(type default)
			)
			(layer "F.SilkS")
		)
		(fp_line
			(start -1.27 -1.7018)
			(end 1.27 -1.7018)
			(stroke
				(width 0.1524)
				(type default)
			)
			(layer "F.SilkS")
		)
		(fp_line
			(start 1.27 1.7018)
			(end -1.27 1.7018)
			(stroke
				(width 0.1524)
				(type default)
			)
			(layer "F.SilkS")
		)
		(fp_line
			(start -1.27 1.7018)
			(end -1.27 -1.7018)
			(stroke
				(width 0.1524)
				(type default)
			)
			(layer "F.SilkS")
		)
		(fp_rect
			(start -1.524 1.9558)
			(end 1.524 -1.9558)
			(stroke
				(width 0)
				(type default)
			)
			(fill no)
			(layer "F.CrtYd")
		)
		(fp_poly
			(pts
				(xy -1.524 -1.9558) (xy 1.524 -1.9558) (xy 1.524 1.9558) (xy -1.524 1.9558)
			)
			(stroke
				(width 0)
				(type default)
			)
			(fill no)
			(layer "F.Fab")
		)
		(pad "1" smd rect
			(at 0.65024 -0.8255 90)
			(size 0.4064 1.2192)
			(layers "F.Cu" "F.Mask" "F.Paste")
			(net "RSTBTN_OUT_N")
		)
		(pad "2" smd rect
			(at 0 -0.8255 90)
			(size 0.4064 1.2192)
			(layers "F.Cu" "F.Mask" "F.Paste")
			(net "BMC_RSTBTN_N")
		)
		(pad "3" smd rect
			(at -0.65024 -0.8255 90)
			(size 0.4064 1.2192)
			(layers "F.Cu" "F.Mask" "F.Paste")
			(net "GND")
		)
		(pad "4" smd rect
			(at -0.65024 0.8255 90)
			(size 0.4064 1.2192)
			(layers "F.Cu" "F.Mask" "F.Paste")
			(net "CPU_EXP_RESET_N")
		)
		(pad "5" smd rect
			(at 0.65024 0.8255 90)
			(size 0.4064 1.2192)
			(layers "F.Cu" "F.Mask" "F.Paste")
			(net "P3V3_STBY")
		)
	)
)
